(kicad_pcb
	(version 20260206)
	(generator "pcbnew")
	(generator_version "10.0")
	(general
		(thickness 1.6)
		(legacy_teardrops no)
	)
	(paper "A4")
	(title_block
		(title "03242023_DA0F0TMBIJ0_F0T_Motherboard_J_brd_V01_OCP.brd")
		(comment 1 "Grand Teton / footprints 2510-2516 of 6105")
	)
	(layers
		(0 "F.Cu" signal "TOP")
		(4 "In1.Cu" signal "GND")
		(6 "In2.Cu" signal "IN1")
		(8 "In3.Cu" signal "GND1")
		(10 "In4.Cu" signal "IN2")
		(12 "In5.Cu" signal "GND2")
		(14 "In6.Cu" signal "IN3")
		(16 "In7.Cu" signal "GND3")
		(18 "In8.Cu" signal "VCC")
		(20 "In9.Cu" signal "VCC1")
		(22 "In10.Cu" signal "GND4")
		(24 "In11.Cu" signal "IN4")
		(26 "In12.Cu" signal "GND5")
		(28 "In13.Cu" signal "IN5")
		(30 "In14.Cu" signal "GND6")
		(32 "In15.Cu" signal "IN6")
		(34 "In16.Cu" signal "GND7")
		(2 "B.Cu" signal "BOTTOM")
		(9 "F.Adhes" user "F.Adhesive")
		(11 "B.Adhes" user "B.Adhesive")
		(13 "F.Paste" user "Package Geometry/Pastemask Top")
		(15 "B.Paste" user "Package Geometry/Pastemask Bottom")
		(5 "F.SilkS" user "Ref Des/Silkscreen Top")
		(7 "B.SilkS" user "Ref Des/Silkscreen Bottom")
		(1 "F.Mask" user "Board Geometry/Soldermask Top")
		(3 "B.Mask" user "Board Geometry/Soldermask Bottom")
		(17 "Dwgs.User" user "User.Drawings")
		(19 "Cmts.User" user "User.Comments")
		(21 "Eco1.User" user "User.Eco1")
		(23 "Eco2.User" user "User.Eco2")
		(25 "Edge.Cuts" user "Board Geometry/Outline")
		(27 "Margin" user)
		(31 "F.CrtYd" user "Package Geometry/Place Bound Top")
		(29 "B.CrtYd" user "Package Geometry/Place Bound Bottom")
		(35 "F.Fab" user "Ref Des/Assembly Top")
		(33 "B.Fab" user "Ref Des/Assembly Bottom")
	)
	(footprint ""
		(layer "F.Cu")
		(at 197.41388 -99.875848 180)
		(property "Reference" "R369"
			(at 0 0 180)
			(layer "F.SilkS")
			(hide yes)
			(effects
				(font
					(size 1.27 1.27)
				)
			)
		)
		(property "Value" ""
			(at 0 0 180)
			(layer "F.Fab")
			(effects
				(font
					(size 1.27 1.27)
				)
			)
		)
		(duplicate_pad_numbers_are_jumpers no)
		(fp_line
			(start 0.7874 0.4064)
			(end -0.7874 0.4064)
			(stroke
				(width 0.1524)
				(type default)
			)
			(layer "F.SilkS")
		)
		(fp_line
			(start 0.7874 -0.4064)
			(end 0.7874 0.4064)
			(stroke
				(width 0.1524)
				(type default)
			)
			(layer "F.SilkS")
		)
		(fp_line
			(start -0.7874 0.4064)
			(end -0.7874 -0.4064)
			(stroke
				(width 0.1524)
				(type default)
			)
			(layer "F.SilkS")
		)
		(fp_line
			(start -0.7874 -0.4064)
			(end 0.7874 -0.4064)
			(stroke
				(width 0.1524)
				(type default)
			)
			(layer "F.SilkS")
		)
		(fp_line
			(start 0.67945 0.3048)
			(end 0.120396 0.3048)
			(stroke
				(width 0.1)
				(type default)
			)
			(layer "F.Fab")
		)
		(fp_line
			(start 0.67945 -0.3048)
			(end 0.67945 0.3048)
			(stroke
				(width 0.1)
				(type default)
			)
			(layer "F.Fab")
		)
		(fp_line
			(start 0.12065 -0.2794)
			(end 0.12065 -0.3048)
			(stroke
				(width 0.1)
				(type default)
			)
			(layer "F.Fab")
		)
		(fp_line
			(start 0.12065 -0.3048)
			(end 0.67945 -0.3048)
			(stroke
				(width 0.1)
				(type default)
			)
			(layer "F.Fab")
		)
		(fp_line
			(start 0.120396 0.3048)
			(end 0.120396 0.2794)
			(stroke
				(width 0.1)
				(type default)
			)
			(layer "F.Fab")
		)
		(fp_line
			(start 0.120396 0.2794)
			(end -0.12065 0.2794)
			(stroke
				(width 0.1)
				(type default)
			)
			(layer "F.Fab")
		)
		(fp_line
			(start -0.12065 0.3048)
			(end -0.67945 0.3048)
			(stroke
				(width 0.1)
				(type default)
			)
			(layer "F.Fab")
		)
		(fp_line
			(start -0.12065 0.2794)
			(end -0.12065 0.3048)
			(stroke
				(width 0.1)
				(type default)
			)
			(layer "F.Fab")
		)
		(fp_line
			(start -0.12065 -0.2794)
			(end 0.12065 -0.2794)
			(stroke
				(width 0.1)
				(type default)
			)
			(layer "F.Fab")
		)
		(fp_line
			(start -0.12065 -0.305054)
			(end -0.12065 -0.2794)
			(stroke
				(width 0.1)
				(type default)
			)
			(layer "F.Fab")
		)
		(fp_line
			(start -0.67945 0.3048)
			(end -0.67945 -0.305054)
			(stroke
				(width 0.1)
				(type default)
			)
			(layer "F.Fab")
		)
		(fp_line
			(start -0.67945 -0.305054)
			(end -0.12065 -0.305054)
			(stroke
				(width 0.1)
				(type default)
			)
			(layer "F.Fab")
		)
		(pad "1" smd circle
			(at -0.40005 0 180)
			(size 0 0)
			(layers "F.Cu" "F.Mask" "F.Paste")
			(net "P3V3_AUX")
		)
		(pad "2" smd circle
			(at 0.40005 0 180)
			(size 0 0)
			(layers "F.Cu" "F.Mask" "F.Paste")
			(net "FM_ADR_ACK")
		)
	)
	(footprint ""
		(layer "F.Cu")
		(at 393.290552 -32.456374 180)
		(property "Reference" "R1514"
			(at 0 0 180)
			(layer "F.SilkS")
			(hide yes)
			(effects
				(font
					(size 1.27 1.27)
				)
			)
		)
		(property "Value" ""
			(at 0 0 180)
			(layer "F.Fab")
			(effects
				(font
					(size 1.27 1.27)
				)
			)
		)
		(duplicate_pad_numbers_are_jumpers no)
		(fp_line
			(start 0.7874 0.4064)
			(end -0.7874 0.4064)
			(stroke
				(width 0.1524)
				(type default)
			)
			(layer "F.SilkS")
		)
		(fp_line
			(start 0.7874 -0.4064)
			(end 0.7874 0.4064)
			(stroke
				(width 0.1524)
				(type default)
			)
			(layer "F.SilkS")
		)
		(fp_line
			(start -0.7874 0.4064)
			(end -0.7874 -0.4064)
			(stroke
				(width 0.1524)
				(type default)
			)
			(layer "F.SilkS")
		)
		(fp_line
			(start -0.7874 -0.4064)
			(end 0.7874 -0.4064)
			(stroke
				(width 0.1524)
				(type default)
			)
			(layer "F.SilkS")
		)
		(fp_line
			(start 0.67945 0.3048)
			(end 0.120396 0.3048)
			(stroke
				(width 0.1)
				(type default)
			)
			(layer "F.Fab")
		)
		(fp_line
			(start 0.67945 -0.3048)
			(end 0.67945 0.3048)
			(stroke
				(width 0.1)
				(type default)
			)
			(layer "F.Fab")
		)
		(fp_line
			(start 0.12065 -0.2794)
			(end 0.12065 -0.3048)
			(stroke
				(width 0.1)
				(type default)
			)
			(layer "F.Fab")
		)
		(fp_line
			(start 0.12065 -0.3048)
			(end 0.67945 -0.3048)
			(stroke
				(width 0.1)
				(type default)
			)
			(layer "F.Fab")
		)
		(fp_line
			(start 0.120396 0.3048)
			(end 0.120396 0.2794)
			(stroke
				(width 0.1)
				(type default)
			)
			(layer "F.Fab")
		)
		(fp_line
			(start 0.120396 0.2794)
			(end -0.12065 0.2794)
			(stroke
				(width 0.1)
				(type default)
			)
			(layer "F.Fab")
		)
		(fp_line
			(start -0.12065 0.3048)
			(end -0.67945 0.3048)
			(stroke
				(width 0.1)
				(type default)
			)
			(layer "F.Fab")
		)
		(fp_line
			(start -0.12065 0.2794)
			(end -0.12065 0.3048)
			(stroke
				(width 0.1)
				(type default)
			)
			(layer "F.Fab")
		)
		(fp_line
			(start -0.12065 -0.2794)
			(end 0.12065 -0.2794)
			(stroke
				(width 0.1)
				(type default)
			)
			(layer "F.Fab")
		)
		(fp_line
			(start -0.12065 -0.305054)
			(end -0.12065 -0.2794)
			(stroke
				(width 0.1)
				(type default)
			)
			(layer "F.Fab")
		)
		(fp_line
			(start -0.67945 0.3048)
			(end -0.67945 -0.305054)
			(stroke
				(width 0.1)
				(type default)
			)
			(layer "F.Fab")
		)
		(fp_line
			(start -0.67945 -0.305054)
			(end -0.12065 -0.305054)
			(stroke
				(width 0.1)
				(type default)
			)
			(layer "F.Fab")
		)
		(pad "1" smd circle
			(at -0.40005 0 180)
			(size 0 0)
			(layers "F.Cu" "F.Mask" "F.Paste")
			(net "RST_PCIE_CPU0_DEV_PERST_N")
		)
		(pad "2" smd circle
			(at 0.40005 0 180)
			(size 0 0)
			(layers "F.Cu" "F.Mask" "F.Paste")
			(net "RST_OCP_V3_1_N")
		)
	)
	(footprint ""
		(layer "F.Cu")
		(at 459.579726 -98.514408)
		(property "Reference" "U66"
			(at -3.89636 -2.009648 0)
			(unlocked yes)
			(layer "F.SilkS")
			(effects
				(font
					(size 0.7874 0.5842)
					(thickness 0.1524)
				)
				(justify left)
			)
		)
		(property "Value" ""
			(at 0 0 0)
			(layer "F.Fab")
			(effects
				(font
					(size 1.27 1.27)
				)
			)
		)
		(duplicate_pad_numbers_are_jumpers no)
		(fp_line
			(start -1.400048 1.100074)
			(end -1.400048 -1.100074)
			(stroke
				(width 0.1524)
				(type default)
			)
			(layer "F.SilkS")
		)
		(fp_line
			(start 1.400048 -1.100074)
			(end -1.400048 -1.100074)
			(stroke
				(width 0.1524)
				(type default)
			)
			(layer "F.SilkS")
		)
		(fp_line
			(start 1.400048 -1.100074)
			(end 1.400048 1.100074)
			(stroke
				(width 0.1524)
				(type default)
			)
			(layer "F.SilkS")
		)
		(fp_line
			(start 1.400048 1.100074)
			(end -1.400048 1.100074)
			(stroke
				(width 0.1524)
				(type default)
			)
			(layer "F.SilkS")
		)
		(fp_poly
			(pts
				(xy -1.03886 -1.265682) (xy -1.54686 -2.281682) (xy -0.53086 -2.281682)
			)
			(stroke
				(width 0)
				(type default)
			)
			(fill yes)
			(layer "F.SilkS")
		)
		(fp_line
			(start -0.674878 -1.100074)
			(end 0.674878 -1.100074)
			(stroke
				(width 0.1)
				(type default)
			)
			(layer "F.Fab")
		)
		(fp_line
			(start -0.674878 1.100074)
			(end -0.674878 -1.100074)
			(stroke
				(width 0.1)
				(type default)
			)
			(layer "F.Fab")
		)
		(fp_line
			(start 0.674878 -1.100074)
			(end 0.674878 1.100074)
			(stroke
				(width 0.1)
				(type default)
			)
			(layer "F.Fab")
		)
		(fp_line
			(start 0.674878 1.100074)
			(end -0.674878 1.100074)
			(stroke
				(width 0.1)
				(type default)
			)
			(layer "F.Fab")
		)
		(fp_poly
			(pts
				(xy -1.590548 -0.649986) (xy -2.606548 -1.157986) (xy -2.606548 -0.141986)
			)
			(stroke
				(width 0)
				(type default)
			)
			(fill yes)
			(layer "F.Fab")
		)
		(pad "1" smd rect
			(at -0.94996 -0.649986 270)
			(size 0.4318 0.6096)
			(layers "F.Cu" "F.Mask" "F.Paste")
			(net "OCP_SFF_AUX_PWR_EN_R1")
		)
		(pad "2" smd rect
			(at -0.94996 0 270)
			(size 0.4318 0.6096)
			(layers "F.Cu" "F.Mask" "F.Paste")
			(net "FM_OCP_SFF_PWR_GOOD")
		)
		(pad "3" smd rect
			(at -0.94996 0.649986 270)
			(size 0.4318 0.6096)
			(layers "F.Cu" "F.Mask" "F.Paste")
			(net "GND")
		)
		(pad "4" smd rect
			(at 0.94996 0.649986 270)
			(size 0.4318 0.6096)
			(layers "F.Cu" "F.Mask" "F.Paste")
			(net "FB_BMC_ISOLATE_R1")
		)
		(pad "5" smd rect
			(at 0.94996 -0.649986 270)
			(size 0.4318 0.6096)
			(layers "F.Cu" "F.Mask" "F.Paste")
			(net "P3V3_AUX")
		)
	)
	(footprint ""
		(layer "F.Cu")
		(at 21.752052 -403.827488)
		(property "Reference" "R3318"
			(at 0 0 0)
			(layer "F.SilkS")
			(hide yes)
			(effects
				(font
					(size 1.27 1.27)
				)
			)
		)
		(property "Value" ""
			(at 0 0 0)
			(layer "F.Fab")
			(effects
				(font
					(size 1.27 1.27)
				)
			)
		)
		(duplicate_pad_numbers_are_jumpers no)
		(fp_line
			(start -0.7874 -0.4064)
			(end 0.7874 -0.4064)
			(stroke
				(width 0.1524)
				(type default)
			)
			(layer "F.SilkS")
		)
		(fp_line
			(start -0.7874 0.4064)
			(end -0.7874 -0.4064)
			(stroke
				(width 0.1524)
				(type default)
			)
			(layer "F.SilkS")
		)
		(fp_line
			(start 0.7874 -0.4064)
			(end 0.7874 0.4064)
			(stroke
				(width 0.1524)
				(type default)
			)
			(layer "F.SilkS")
		)
		(fp_line
			(start 0.7874 0.4064)
			(end -0.7874 0.4064)
			(stroke
				(width 0.1524)
				(type default)
			)
			(layer "F.SilkS")
		)
		(fp_line
			(start -0.67945 -0.305054)
			(end -0.12065 -0.305054)
			(stroke
				(width 0.1)
				(type default)
			)
			(layer "F.Fab")
		)
		(fp_line
			(start -0.67945 0.3048)
			(end -0.67945 -0.305054)
			(stroke
				(width 0.1)
				(type default)
			)
			(layer "F.Fab")
		)
		(fp_line
			(start -0.12065 -0.305054)
			(end -0.12065 -0.2794)
			(stroke
				(width 0.1)
				(type default)
			)
			(layer "F.Fab")
		)
		(fp_line
			(start -0.12065 -0.2794)
			(end 0.12065 -0.2794)
			(stroke
				(width 0.1)
				(type default)
			)
			(layer "F.Fab")
		)
		(fp_line
			(start -0.12065 0.2794)
			(end -0.12065 0.3048)
			(stroke
				(width 0.1)
				(type default)
			)
			(layer "F.Fab")
		)
		(fp_line
			(start -0.12065 0.3048)
			(end -0.67945 0.3048)
			(stroke
				(width 0.1)
				(type default)
			)
			(layer "F.Fab")
		)
		(fp_line
			(start 0.120396 0.2794)
			(end -0.12065 0.2794)
			(stroke
				(width 0.1)
				(type default)
			)
			(layer "F.Fab")
		)
		(fp_line
			(start 0.120396 0.3048)
			(end 0.120396 0.2794)
			(stroke
				(width 0.1)
				(type default)
			)
			(layer "F.Fab")
		)
		(fp_line
			(start 0.12065 -0.3048)
			(end 0.67945 -0.3048)
			(stroke
				(width 0.1)
				(type default)
			)
			(layer "F.Fab")
		)
		(fp_line
			(start 0.12065 -0.2794)
			(end 0.12065 -0.3048)
			(stroke
				(width 0.1)
				(type default)
			)
			(layer "F.Fab")
		)
		(fp_line
			(start 0.67945 -0.3048)
			(end 0.67945 0.3048)
			(stroke
				(width 0.1)
				(type default)
			)
			(layer "F.Fab")
		)
		(fp_line
			(start 0.67945 0.3048)
			(end 0.120396 0.3048)
			(stroke
				(width 0.1)
				(type default)
			)
			(layer "F.Fab")
		)
		(pad "1" smd circle
			(at -0.40005 0)
			(size 0 0)
			(layers "F.Cu" "F.Mask" "F.Paste")
			(net "P3V3_AUX")
		)
		(pad "2" smd circle
			(at 0.40005 0)
			(size 0 0)
			(layers "F.Cu" "F.Mask" "F.Paste")
			(net "GPU_FPGA_READY")
		)
	)
	(footprint ""
		(layer "F.Cu")
		(at 106.3244 -252.956568 -90)
		(property "Reference" "C271"
			(at 0 0 270)
			(layer "F.SilkS")
			(hide yes)
			(effects
				(font
					(size 1.27 1.27)
				)
			)
		)
		(property "Value" ""
			(at 0 0 270)
			(layer "F.Fab")
			(effects
				(font
					(size 1.27 1.27)
				)
			)
		)
		(duplicate_pad_numbers_are_jumpers no)
		(fp_line
			(start -0.7874 0.4064)
			(end -0.7874 -0.4064)
			(stroke
				(width 0.1524)
				(type default)
			)
			(layer "F.SilkS")
		)
		(fp_line
			(start 0.7874 0.4064)
			(end -0.7874 0.4064)
			(stroke
				(width 0.1524)
				(type default)
			)
			(layer "F.SilkS")
		)
		(fp_line
			(start -0.7874 -0.4064)
			(end 0.7874 -0.4064)
			(stroke
				(width 0.1524)
				(type default)
			)
			(layer "F.SilkS")
		)
		(fp_line
			(start 0.7874 -0.4064)
			(end 0.7874 0.4064)
			(stroke
				(width 0.1524)
				(type default)
			)
			(layer "F.SilkS")
		)
		(fp_line
			(start -0.67945 0.3048)
			(end -0.67945 -0.305054)
			(stroke
				(width 0.1)
				(type default)
			)
			(layer "F.Fab")
		)
		(fp_line
			(start -0.12065 0.3048)
			(end -0.67945 0.3048)
			(stroke
				(width 0.1)
				(type default)
			)
			(layer "F.Fab")
		)
		(fp_line
			(start 0.120396 0.3048)
			(end 0.120396 0.2794)
			(stroke
				(width 0.1)
				(type default)
			)
			(layer "F.Fab")
		)
		(fp_line
			(start 0.67945 0.3048)
			(end 0.120396 0.3048)
			(stroke
				(width 0.1)
				(type default)
			)
			(layer "F.Fab")
		)
		(fp_line
			(start -0.12065 0.2794)
			(end -0.12065 0.3048)
			(stroke
				(width 0.1)
				(type default)
			)
			(layer "F.Fab")
		)
		(fp_line
			(start 0.120396 0.2794)
			(end -0.12065 0.2794)
			(stroke
				(width 0.1)
				(type default)
			)
			(layer "F.Fab")
		)
		(fp_line
			(start -0.12065 -0.2794)
			(end 0.12065 -0.2794)
			(stroke
				(width 0.1)
				(type default)
			)
			(layer "F.Fab")
		)
		(fp_line
			(start 0.12065 -0.2794)
			(end 0.12065 -0.3048)
			(stroke
				(width 0.1)
				(type default)
			)
			(layer "F.Fab")
		)
		(fp_line
			(start 0.12065 -0.3048)
			(end 0.67945 -0.3048)
			(stroke
				(width 0.1)
				(type default)
			)
			(layer "F.Fab")
		)
		(fp_line
			(start 0.67945 -0.3048)
			(end 0.67945 0.3048)
			(stroke
				(width 0.1)
				(type default)
			)
			(layer "F.Fab")
		)
		(fp_line
			(start -0.67945 -0.305054)
			(end -0.12065 -0.305054)
			(stroke
				(width 0.1)
				(type default)
			)
			(layer "F.Fab")
		)
		(fp_line
			(start -0.12065 -0.305054)
			(end -0.12065 -0.2794)
			(stroke
				(width 0.1)
				(type default)
			)
			(layer "F.Fab")
		)
		(pad "1" smd circle
			(at -0.40005 0 270)
			(size 0 0)
			(layers "F.Cu" "F.Mask" "F.Paste")
			(net "PVCCIN_CPU1")
		)
		(pad "2" smd circle
			(at 0.40005 0 270)
			(size 0 0)
			(layers "F.Cu" "F.Mask" "F.Paste")
			(net "GND")
		)
	)
	(footprint ""
		(layer "F.Cu")
		(at 422.66616 -143.675608 90)
		(property "Reference" "PR4225"
			(at 0 0 90)
			(layer "F.SilkS")
			(hide yes)
			(effects
				(font
					(size 1.27 1.27)
				)
			)
		)
		(property "Value" ""
			(at 0 0 90)
			(layer "F.Fab")
			(effects
				(font
					(size 1.27 1.27)
				)
			)
		)
		(duplicate_pad_numbers_are_jumpers no)
		(fp_line
			(start 0.7874 -0.4064)
			(end 0.7874 0.4064)
			(stroke
				(width 0.1524)
				(type default)
			)
			(layer "F.SilkS")
		)
		(fp_line
			(start -0.7874 -0.4064)
			(end 0.7874 -0.4064)
			(stroke
				(width 0.1524)
				(type default)
			)
			(layer "F.SilkS")
		)
		(fp_line
			(start 0.7874 0.4064)
			(end -0.7874 0.4064)
			(stroke
				(width 0.1524)
				(type default)
			)
			(layer "F.SilkS")
		)
		(fp_line
			(start -0.7874 0.4064)
			(end -0.7874 -0.4064)
			(stroke
				(width 0.1524)
				(type default)
			)
			(layer "F.SilkS")
		)
		(fp_line
			(start -0.12065 -0.305054)
			(end -0.12065 -0.2794)
			(stroke
				(width 0.1)
				(type default)
			)
			(layer "F.Fab")
		)
		(fp_line
			(start -0.67945 -0.305054)
			(end -0.12065 -0.305054)
			(stroke
				(width 0.1)
				(type default)
			)
			(layer "F.Fab")
		)
		(fp_line
			(start 0.67945 -0.3048)
			(end 0.67945 0.3048)
			(stroke
				(width 0.1)
				(type default)
			)
			(layer "F.Fab")
		)
		(fp_line
			(start 0.12065 -0.3048)
			(end 0.67945 -0.3048)
			(stroke
				(width 0.1)
				(type default)
			)
			(layer "F.Fab")
		)
		(fp_line
			(start 0.12065 -0.2794)
			(end 0.12065 -0.3048)
			(stroke
				(width 0.1)
				(type default)
			)
			(layer "F.Fab")
		)
		(fp_line
			(start -0.12065 -0.2794)
			(end 0.12065 -0.2794)
			(stroke
				(width 0.1)
				(type default)
			)
			(layer "F.Fab")
		)
		(fp_line
			(start 0.120396 0.2794)
			(end -0.12065 0.2794)
			(stroke
				(width 0.1)
				(type default)
			)
			(layer "F.Fab")
		)
		(fp_line
			(start -0.12065 0.2794)
			(end -0.12065 0.3048)
			(stroke
				(width 0.1)
				(type default)
			)
			(layer "F.Fab")
		)
		(fp_line
			(start 0.67945 0.3048)
			(end 0.120396 0.3048)
			(stroke
				(width 0.1)
				(type default)
			)
			(layer "F.Fab")
		)
		(fp_line
			(start 0.120396 0.3048)
			(end 0.120396 0.2794)
			(stroke
				(width 0.1)
				(type default)
			)
			(layer "F.Fab")
		)
		(fp_line
			(start -0.12065 0.3048)
			(end -0.67945 0.3048)
			(stroke
				(width 0.1)
				(type default)
			)
			(layer "F.Fab")
		)
		(fp_line
			(start -0.67945 0.3048)
			(end -0.67945 -0.305054)
			(stroke
				(width 0.1)
				(type default)
			)
			(layer "F.Fab")
		)
		(pad "1" smd circle
			(at -0.40005 0 90)
			(size 0 0)
			(layers "F.Cu" "F.Mask" "F.Paste")
			(net "NC_PVCCINFAON_CPU0_ACSP7")
		)
		(pad "2" smd circle
			(at 0.40005 0 90)
			(size 0 0)
			(layers "F.Cu" "F.Mask" "F.Paste")
			(net "GND")
		)
	)
	(footprint ""
		(layer "F.Cu")
		(at 112.604804 -344.029284 90)
		(property "Reference" "PC582"
			(at 0 0 90)
			(layer "F.SilkS")
			(hide yes)
			(effects
				(font
					(size 1.27 1.27)
				)
			)
		)
		(property "Value" ""
			(at 0 0 90)
			(layer "F.Fab")
			(effects
				(font
					(size 1.27 1.27)
				)
			)
		)
		(duplicate_pad_numbers_are_jumpers no)
		(fp_line
			(start -3.400044 1.249934)
			(end 3.400044 1.249934)
			(stroke
				(width 0.1524)
				(type default)
			)
			(layer "F.SilkS")
		)
		(fp_circle
			(center 0 1.249934)
			(end 0 4.649978)
			(stroke
				(width 0.1524)
				(type default)
			)
			(fill no)
			(layer "F.SilkS")
		)
		(fp_poly
			(pts
				(arc
					(start -3.400044 1.249934)
					(mid 0 4.649978)
					(end 3.400044 1.249934)
				)
			)
			(stroke
				(width 0)
				(type default)
			)
			(fill yes)
			(layer "F.SilkS")
		)
		(fp_circle
			(center 0 1.249934)
			(end 0 4.649978)
			(stroke
				(width 0.1)
				(type default)
			)
			(fill no)
			(layer "F.Fab")
		)
		(pad "1" thru_hole rect
			(at 0 0 90)
			(size 1.524 1.524)
			(drill 1.016)
			(layers "*.Cu" "*.Mask")
			(remove_unused_layers no)
			(net "SW_P12V_PVCCIN_CPU1_FLT")
			(clearance 0)
			(padstack
				(mode front_inner_back)
				(layer "Inner"
					(shape circle)
					(size 1.524 1.524)
					(clearance 0)
				)
				(layer "B.Cu"
					(shape rect)
					(size 1.524 1.524)
					(clearance 0)
				)
			)
		)
		(pad "2" thru_hole circle
			(at 0 2.500122 90)
			(size 1.524 1.524)
			(drill 1.016)
			(layers "*.Cu" "*.Mask")
			(remove_unused_layers no)
			(net "GND")
			(clearance 0)
		)
	)
)
